FILE_TYPE = MACRO_DRAWING;
SET COLOR_WIRE YELLOW;
SET COLOR_PROP ORANGE;
SET COLOR_DOT WHITE;
SET COLOR_ARC YELLOW;
SET COLOR_BODY GREEN;
SET COLOR_NOTE PURPLE;
SET PROP_DISPLAY VALUE;
SET PAGE_NUMBER P179;
FORCEADD QUANTA_TITLE_BLOCK_C..1
(0 0);
FORCEPROP 1 LAST CUSTOM_TXT_CDS <NAME_2>
J 0
(-3175 50);
FORCEPROP 1 LAST CUSTOM_TXT_CDS <NAME_1>
J 0
(-3175 175);
FORCEPROP 1 LAST CUSTOM_TXT_CDS <Q_NUMBER>
J 0
(-1403 103);
DISPLAY 1.212766 (-1403 103);
FORCEPROP 1 LAST CUSTOM_TXT_CDS <Q_PROJ>
J 0
(-2382 102);
DISPLAY 1.212766 (-2382 102);
FORCEPROP 1 LAST CUSTOM_TXT_CDS <Q_REV>
J 0
(-184 103);
DISPLAY 1.212766 (-184 103);
FORCEPROP 1 LAST CUSTOM_TXT_CDS <CON_LAST_MODIFIED>
J 0
(-1885 15);
DISPLAY 0.978723 (-1885 15);
FORCEPROP 1 LAST CUSTOM_TXT_CDS <CON_PAGE_NUM> OF <CON_TOTAL_PAGES>
J 0
(-446 18);
DISPLAY 0.978723 (-446 18);
FORCEPROP 1 LAST Q_TITLE Blank
J 0
(-9366 26);
DISPLAY 2.446809 (-9366 26);
PAINT GREEN (-9366 26);
FORCEPROP 1 LAST Q_DEPT BU9
J 1
(-3763 49);
DISPLAY 1.957447 (-3763 49);
PAINT GREEN (-3763 49);
FORCEPROP 0 LAST CDS_CON_LAST_MODIFIED Wed Jul 21 11:37:45 2021
J 0
(-1885 15);
DISPLAY INVISIBLE (-1885 15);
FORCEPROP 2 LAST PAGE_BORDER TRUE
J 0
(-7890 5250);
DISPLAY 0.638298 (-7890 5250);
PAINT PINK (-7890 5250);
DISPLAY INVISIBLE (-7890 5250);
FORCEPROP 2 LAST CDS_LIB pure_quanta
J 0
(0 0);
DISPLAY INVISIBLE (0 0);
FORCEPROP 1 LAST CDS_LMAN_SYM_OUTLINE -9475,6775,100,-125
J 0
(0 0);
DISPLAY 0.468085 (0 0);
PAINT GREEN (0 0);
DISPLAY INVISIBLE (0 0);
FORCEPROP 1 LAST COMMENT_BODY TRUE
J 0
(12 -13);
DISPLAY 0.978723 (12 -13);
PAINT GREEN (12 -13);
DISPLAY INVISIBLE (12 -13);
FORCEPROP 2 LAST CUSTOM_TXT_CDS <XR_PAGE_TITLE>
J 0
(-7890 5250);
DISPLAY 0.638298 (-7890 5250);
PAINT PINK (-7890 5250);
DISPLAY INVISIBLE (-7890 5250);
FORCEPROP 2 LAST CDS_XR_PAGE_TITLE CR-180 : @T6G_MB_LIB.T6G(SCH_1):PAGE180
J 0
(-7890 5250);
DISPLAY 0.638298 (-7890 5250);
PAINT PINK (-7890 5250);
DISPLAY INVISIBLE (-7890 5250);
QUIT
